(kicad_pcb
	(version 20260206)
	(generator "pcbnew")
	(generator_version "10.0")
	(general
		(thickness 1.6)
		(legacy_teardrops no)
	)
	(paper "A4")
	(title_block
		(title "Bryce Canyon_SCC_16316-1_OCP.brd")
		(comment 1 "Bryce Canyon / footprints 1315-1323 of 1561")
	)
	(layers
		(0 "F.Cu" signal "TOP")
		(4 "In1.Cu" signal "L2GND")
		(6 "In2.Cu" signal "L3")
		(8 "In3.Cu" signal "L4VCC")
		(10 "In4.Cu" signal "L5VCC")
		(12 "In5.Cu" signal "L6")
		(14 "In6.Cu" signal "L7GND")
		(2 "B.Cu" signal "BOTTOM")
		(9 "F.Adhes" user "F.Adhesive")
		(11 "B.Adhes" user "B.Adhesive")
		(13 "F.Paste" user "Package Geometry/Pastemask Top")
		(15 "B.Paste" user "Package Geometry/Pastemask Bottom")
		(5 "F.SilkS" user "Ref Des/Silkscreen Top")
		(7 "B.SilkS" user "Ref Des/Silkscreen Bottom")
		(1 "F.Mask" user "Board Geometry/Soldermask Top")
		(3 "B.Mask" user "Board Geometry/Soldermask Bottom")
		(17 "Dwgs.User" user "User.Drawings")
		(19 "Cmts.User" user "User.Comments")
		(21 "Eco1.User" user "User.Eco1")
		(23 "Eco2.User" user "User.Eco2")
		(25 "Edge.Cuts" user "Board Geometry/Outline")
		(27 "Margin" user)
		(31 "F.CrtYd" user "Package Geometry/Place Bound Top")
		(29 "B.CrtYd" user "Package Geometry/Place Bound Bottom")
		(35 "F.Fab" user "Ref Des/Assembly Top")
		(33 "B.Fab" user "Ref Des/Assembly Bottom")
	)
	(footprint ""
		(layer "B.Cu")
		(at 159.512 -52.07)
		(property "Reference" "R192"
			(at 0 0 0)
			(layer "B.SilkS")
			(hide yes)
			(effects
				(font
					(size 1.27 1.27)
				)
				(justify mirror)
			)
		)
		(property "Value" "2K2R2F-GP"
			(at -0.064008 -3.993896 0)
			(unlocked yes)
			(layer "B.Fab")
			(hide yes)
			(effects
				(font
					(size 1.016 1.016)
					(thickness 0.1524)
				)
				(justify mirror)
			)
		)
		(property "Device Type" "R402H16"
			(at -0.064008 -5.517896 0)
			(unlocked yes)
			(layer "B.Fab")
			(hide yes)
			(effects
				(font
					(size 1.016 1.016)
					(thickness 0.1524)
				)
				(justify mirror)
			)
		)
		(duplicate_pad_numbers_are_jumpers no)
		(fp_line
			(start -0.508 -0.9398)
			(end 0.508 -0.9398)
			(stroke
				(width 0.1524)
				(type default)
			)
			(layer "B.SilkS")
		)
		(fp_line
			(start 0.508 -0.9398)
			(end 0.508 0.9398)
			(stroke
				(width 0.1524)
				(type default)
			)
			(layer "B.SilkS")
		)
		(fp_rect
			(start 0.508 0.9398)
			(end -0.508 -0.9398)
			(stroke
				(width 0)
				(type default)
			)
			(fill no)
			(layer "B.CrtYd")
		)
		(fp_rect
			(start 0.508 0.9398)
			(end -0.508 -0.9398)
			(stroke
				(width 0)
				(type default)
			)
			(fill no)
			(layer "B.Fab")
		)
		(pad "1" smd custom
			(at 0 -0.4445 180)
			(size 0.1397 0.1397)
			(layers "B.Cu" "B.Mask" "B.Paste")
			(net "P1V8_C")
			(options
				(clearance outline)
				(anchor circle)
			)
			(primitives
				(gr_poly
					(pts
						(arc
							(start -0.1778 0.2794)
							(mid -0.249642 0.249642)
							(end -0.2794 0.1778)
						)
						(arc
							(start -0.2794 -0.1778)
							(mid -0.249642 -0.249642)
							(end -0.1778 -0.2794)
						)
						(arc
							(start 0.1778 -0.2794)
							(mid 0.249642 -0.249642)
							(end 0.2794 -0.1778)
						)
						(arc
							(start 0.2794 0.1778)
							(mid 0.249642 0.249642)
							(end 0.1778 0.2794)
						)
					)
					(width 0)
					(fill yes)
				)
			)
		)
		(pad "2" smd custom
			(at 0 0.4445 180)
			(size 0.1397 0.1397)
			(layers "B.Cu" "B.Mask" "B.Paste")
			(net "SIO_CLK_0")
			(options
				(clearance outline)
				(anchor circle)
			)
			(primitives
				(gr_poly
					(pts
						(arc
							(start -0.1778 0.2794)
							(mid -0.249642 0.249642)
							(end -0.2794 0.1778)
						)
						(arc
							(start -0.2794 -0.1778)
							(mid -0.249642 -0.249642)
							(end -0.1778 -0.2794)
						)
						(arc
							(start 0.1778 -0.2794)
							(mid 0.249642 -0.249642)
							(end 0.2794 -0.1778)
						)
						(arc
							(start 0.2794 0.1778)
							(mid 0.249642 0.249642)
							(end 0.1778 0.2794)
						)
					)
					(width 0)
					(fill yes)
				)
			)
		)
	)
	(footprint ""
		(layer "B.Cu")
		(at 201.676 -28.575 90)
		(property "Reference" "L25"
			(at 0 0 90)
			(layer "B.SilkS")
			(hide yes)
			(effects
				(font
					(size 1.27 1.27)
				)
				(justify mirror)
			)
		)
		(property "Value" "MPZ2012S601AT-GP"
			(at 0 -4.2418 90)
			(unlocked yes)
			(layer "B.Fab")
			(hide yes)
			(effects
				(font
					(size 1.016 1.016)
					(thickness 0.1524)
				)
				(justify mirror)
			)
		)
		(property "Device Type" "L805H42"
			(at 0 -5.7912 90)
			(unlocked yes)
			(layer "B.Fab")
			(hide yes)
			(effects
				(font
					(size 1.016 1.016)
					(thickness 0.1524)
				)
				(justify mirror)
			)
		)
		(duplicate_pad_numbers_are_jumpers no)
		(fp_line
			(start 0.889 -1.7018)
			(end -0.889 -1.7018)
			(stroke
				(width 0.1524)
				(type default)
			)
			(layer "B.SilkS")
		)
		(fp_line
			(start -0.889 -1.7018)
			(end -0.889 1.7018)
			(stroke
				(width 0.1524)
				(type default)
			)
			(layer "B.SilkS")
		)
		(fp_line
			(start 0.889 1.7018)
			(end 0.889 -1.7018)
			(stroke
				(width 0.1524)
				(type default)
			)
			(layer "B.SilkS")
		)
		(fp_line
			(start -0.889 1.7018)
			(end 0.889 1.7018)
			(stroke
				(width 0.1524)
				(type default)
			)
			(layer "B.SilkS")
		)
		(fp_rect
			(start 0.9652 1.778)
			(end -0.9652 -1.778)
			(stroke
				(width 0)
				(type default)
			)
			(fill no)
			(layer "B.CrtYd")
		)
		(fp_rect
			(start 0.9652 1.778)
			(end -0.9652 -1.778)
			(stroke
				(width 0)
				(type default)
			)
			(fill no)
			(layer "B.Fab")
		)
		(pad "1" smd rect
			(at 0 -0.9652 270)
			(size 1.397 1.143)
			(layers "B.Cu" "B.Mask" "B.Paste")
			(net "PCE_VDDH")
		)
		(pad "2" smd rect
			(at 0 0.9652 270)
			(size 1.397 1.143)
			(layers "B.Cu" "B.Mask" "B.Paste")
			(net "P1V5_C")
		)
	)
	(footprint ""
		(layer "B.Cu")
		(at 121.2596 -89.5604 180)
		(property "Reference" "R302"
			(at 0 0 0)
			(layer "B.SilkS")
			(hide yes)
			(effects
				(font
					(size 1.27 1.27)
				)
				(justify mirror)
			)
		)
		(property "Value" "4K75R2F-1-GP"
			(at -0.064008 -3.993896 180)
			(unlocked yes)
			(layer "B.Fab")
			(hide yes)
			(effects
				(font
					(size 1.016 1.016)
					(thickness 0.1524)
				)
				(justify mirror)
			)
		)
		(property "Device Type" "R402H16"
			(at -0.064008 -5.517896 180)
			(unlocked yes)
			(layer "B.Fab")
			(hide yes)
			(effects
				(font
					(size 1.016 1.016)
					(thickness 0.1524)
				)
				(justify mirror)
			)
		)
		(duplicate_pad_numbers_are_jumpers no)
		(fp_line
			(start 0.508 -0.9398)
			(end 0.508 0.9398)
			(stroke
				(width 0.1524)
				(type default)
			)
			(layer "B.SilkS")
		)
		(fp_line
			(start -0.508 -0.9398)
			(end 0.508 -0.9398)
			(stroke
				(width 0.1524)
				(type default)
			)
			(layer "B.SilkS")
		)
		(fp_rect
			(start 0.508 0.9398)
			(end -0.508 -0.9398)
			(stroke
				(width 0)
				(type default)
			)
			(fill no)
			(layer "B.CrtYd")
		)
		(fp_rect
			(start 0.508 0.9398)
			(end -0.508 -0.9398)
			(stroke
				(width 0)
				(type default)
			)
			(fill no)
			(layer "B.Fab")
		)
		(pad "1" smd custom
			(at 0 -0.4445)
			(size 0.1397 0.1397)
			(layers "B.Cu" "B.Mask" "B.Paste")
			(net "P1V8_E")
			(options
				(clearance outline)
				(anchor circle)
			)
			(primitives
				(gr_poly
					(pts
						(arc
							(start -0.1778 0.2794)
							(mid -0.249642 0.249642)
							(end -0.2794 0.1778)
						)
						(arc
							(start -0.2794 -0.1778)
							(mid -0.249642 -0.249642)
							(end -0.1778 -0.2794)
						)
						(arc
							(start 0.1778 -0.2794)
							(mid 0.249642 -0.249642)
							(end 0.2794 -0.1778)
						)
						(arc
							(start 0.2794 0.1778)
							(mid 0.249642 0.249642)
							(end 0.1778 0.2794)
						)
					)
					(width 0)
					(fill yes)
				)
			)
		)
		(pad "2" smd custom
			(at 0 0.4445)
			(size 0.1397 0.1397)
			(layers "B.Cu" "B.Mask" "B.Paste")
			(net "ICE_TCK")
			(options
				(clearance outline)
				(anchor circle)
			)
			(primitives
				(gr_poly
					(pts
						(arc
							(start -0.1778 0.2794)
							(mid -0.249642 0.249642)
							(end -0.2794 0.1778)
						)
						(arc
							(start -0.2794 -0.1778)
							(mid -0.249642 -0.249642)
							(end -0.1778 -0.2794)
						)
						(arc
							(start 0.1778 -0.2794)
							(mid 0.249642 -0.249642)
							(end 0.2794 -0.1778)
						)
						(arc
							(start 0.2794 0.1778)
							(mid 0.249642 0.249642)
							(end 0.1778 0.2794)
						)
					)
					(width 0)
					(fill yes)
				)
			)
		)
	)
	(footprint ""
		(layer "B.Cu")
		(at 181.443884 -70.245732 90)
		(property "Reference" "R231"
			(at 0 0 90)
			(layer "B.SilkS")
			(hide yes)
			(effects
				(font
					(size 1.27 1.27)
				)
				(justify mirror)
			)
		)
		(property "Value" "10KR2F-2-GP"
			(at -0.064008 -3.993896 90)
			(unlocked yes)
			(layer "B.Fab")
			(hide yes)
			(effects
				(font
					(size 1.016 1.016)
					(thickness 0.1524)
				)
				(justify mirror)
			)
		)
		(property "Device Type" "R402H16"
			(at -0.064008 -5.517896 90)
			(unlocked yes)
			(layer "B.Fab")
			(hide yes)
			(effects
				(font
					(size 1.016 1.016)
					(thickness 0.1524)
				)
				(justify mirror)
			)
		)
		(duplicate_pad_numbers_are_jumpers no)
		(fp_line
			(start 0.508 -0.9398)
			(end 0.508 0.9398)
			(stroke
				(width 0.1524)
				(type default)
			)
			(layer "B.SilkS")
		)
		(fp_line
			(start -0.508 -0.9398)
			(end 0.508 -0.9398)
			(stroke
				(width 0.1524)
				(type default)
			)
			(layer "B.SilkS")
		)
		(fp_rect
			(start 0.508 0.9398)
			(end -0.508 -0.9398)
			(stroke
				(width 0)
				(type default)
			)
			(fill no)
			(layer "B.CrtYd")
		)
		(fp_rect
			(start 0.508 0.9398)
			(end -0.508 -0.9398)
			(stroke
				(width 0)
				(type default)
			)
			(fill no)
			(layer "B.Fab")
		)
		(pad "1" smd custom
			(at 0 -0.4445 270)
			(size 0.1397 0.1397)
			(layers "B.Cu" "B.Mask" "B.Paste")
			(net "P1V8_C")
			(options
				(clearance outline)
				(anchor circle)
			)
			(primitives
				(gr_poly
					(pts
						(arc
							(start -0.1778 0.2794)
							(mid -0.249642 0.249642)
							(end -0.2794 0.1778)
						)
						(arc
							(start -0.2794 -0.1778)
							(mid -0.249642 -0.249642)
							(end -0.1778 -0.2794)
						)
						(arc
							(start 0.1778 -0.2794)
							(mid 0.249642 -0.249642)
							(end 0.2794 -0.1778)
						)
						(arc
							(start 0.2794 0.1778)
							(mid 0.249642 0.249642)
							(end 0.1778 0.2794)
						)
					)
					(width 0)
					(fill yes)
				)
			)
		)
		(pad "2" smd custom
			(at 0 0.4445 270)
			(size 0.1397 0.1397)
			(layers "B.Cu" "B.Mask" "B.Paste")
			(net "IOC_WP_N")
			(options
				(clearance outline)
				(anchor circle)
			)
			(primitives
				(gr_poly
					(pts
						(arc
							(start -0.1778 0.2794)
							(mid -0.249642 0.249642)
							(end -0.2794 0.1778)
						)
						(arc
							(start -0.2794 -0.1778)
							(mid -0.249642 -0.249642)
							(end -0.1778 -0.2794)
						)
						(arc
							(start 0.1778 -0.2794)
							(mid 0.249642 -0.249642)
							(end 0.2794 -0.1778)
						)
						(arc
							(start 0.2794 0.1778)
							(mid 0.249642 0.249642)
							(end 0.1778 0.2794)
						)
					)
					(width 0)
					(fill yes)
				)
			)
		)
	)
	(footprint ""
		(layer "B.Cu")
		(at 89.465912 -71.040498)
		(property "Reference" "L2"
			(at 0 0 0)
			(layer "B.SilkS")
			(hide yes)
			(effects
				(font
					(size 1.27 1.27)
				)
				(justify mirror)
			)
		)
		(property "Value" "MPZ2012S601AT-GP"
			(at 0 -4.2418 0)
			(unlocked yes)
			(layer "B.Fab")
			(hide yes)
			(effects
				(font
					(size 1.016 1.016)
					(thickness 0.1524)
				)
				(justify mirror)
			)
		)
		(property "Device Type" "L805H42"
			(at 0 -5.7912 0)
			(unlocked yes)
			(layer "B.Fab")
			(hide yes)
			(effects
				(font
					(size 1.016 1.016)
					(thickness 0.1524)
				)
				(justify mirror)
			)
		)
		(duplicate_pad_numbers_are_jumpers no)
		(fp_line
			(start -0.889 -1.7018)
			(end -0.889 1.7018)
			(stroke
				(width 0.1524)
				(type default)
			)
			(layer "B.SilkS")
		)
		(fp_line
			(start -0.889 1.7018)
			(end 0.889 1.7018)
			(stroke
				(width 0.1524)
				(type default)
			)
			(layer "B.SilkS")
		)
		(fp_line
			(start 0.889 -1.7018)
			(end -0.889 -1.7018)
			(stroke
				(width 0.1524)
				(type default)
			)
			(layer "B.SilkS")
		)
		(fp_line
			(start 0.889 1.7018)
			(end 0.889 -1.7018)
			(stroke
				(width 0.1524)
				(type default)
			)
			(layer "B.SilkS")
		)
		(fp_rect
			(start 0.9652 1.778)
			(end -0.9652 -1.778)
			(stroke
				(width 0)
				(type default)
			)
			(fill no)
			(layer "B.CrtYd")
		)
		(fp_rect
			(start 0.9652 1.778)
			(end -0.9652 -1.778)
			(stroke
				(width 0)
				(type default)
			)
			(fill no)
			(layer "B.Fab")
		)
		(pad "1" smd rect
			(at 0 -0.9652 180)
			(size 1.397 1.143)
			(layers "B.Cu" "B.Mask" "B.Paste")
			(net "SYSPLL_VDDA18")
		)
		(pad "2" smd rect
			(at 0 0.9652 180)
			(size 1.397 1.143)
			(layers "B.Cu" "B.Mask" "B.Paste")
			(net "P1V8_E")
		)
	)
	(footprint ""
		(layer "B.Cu")
		(at 131.38277 -44.379388 180)
		(property "Reference" "C29"
			(at 0 0 0)
			(layer "B.SilkS")
			(hide yes)
			(effects
				(font
					(size 1.27 1.27)
				)
				(justify mirror)
			)
		)
		(property "Value" "SCD01U16V1KX-GP"
			(at 2.8321 -1.7399 180)
			(unlocked yes)
			(layer "B.Fab")
			(hide yes)
			(effects
				(font
					(size 1.016 1.016)
					(thickness 0.1524)
				)
				(justify mirror)
			)
		)
		(property "Device Type" "C0201H13"
			(at 2.8321 -3.2639 180)
			(unlocked yes)
			(layer "B.Fab")
			(hide yes)
			(effects
				(font
					(size 1.016 1.016)
					(thickness 0.1524)
				)
				(justify mirror)
			)
		)
		(duplicate_pad_numbers_are_jumpers no)
		(fp_rect
			(start 0.2794 0.6477)
			(end -0.2794 -0.6477)
			(stroke
				(width 0)
				(type default)
			)
			(fill no)
			(layer "B.CrtYd")
		)
		(fp_rect
			(start 0.2794 0.6477)
			(end -0.2794 -0.6477)
			(stroke
				(width 0)
				(type default)
			)
			(fill no)
			(layer "B.Fab")
		)
		(pad "1" smd custom
			(at 0 -0.2794)
			(size 0.0762 0.0762)
			(layers "B.Cu" "B.Mask" "B.Paste")
			(net "PHY_DPB_TO_SCC_29_DP")
			(options
				(clearance outline)
				(anchor circle)
			)
			(primitives
				(gr_poly
					(pts
						(arc
							(start 0.1524 0.127)
							(mid 0.137521 0.162921)
							(end 0.1016 0.1778)
						)
						(arc
							(start -0.1016 0.1778)
							(mid -0.137521 0.162921)
							(end -0.1524 0.127)
						)
						(arc
							(start -0.1524 -0.127)
							(mid -0.137521 -0.162921)
							(end -0.1016 -0.1778)
						)
						(arc
							(start 0.1016 -0.1778)
							(mid 0.137521 -0.162921)
							(end 0.1524 -0.127)
						)
					)
					(width 0)
					(fill yes)
				)
			)
		)
		(pad "2" smd custom
			(at 0 0.2794)
			(size 0.0762 0.0762)
			(layers "B.Cu" "B.Mask" "B.Paste")
			(net "PHY_DPB_TO_SCC_C_29_DP")
			(options
				(clearance outline)
				(anchor circle)
			)
			(primitives
				(gr_poly
					(pts
						(arc
							(start 0.1524 0.127)
							(mid 0.137521 0.162921)
							(end 0.1016 0.1778)
						)
						(arc
							(start -0.1016 0.1778)
							(mid -0.137521 0.162921)
							(end -0.1524 0.127)
						)
						(arc
							(start -0.1524 -0.127)
							(mid -0.137521 -0.162921)
							(end -0.1016 -0.1778)
						)
						(arc
							(start 0.1016 -0.1778)
							(mid 0.137521 -0.162921)
							(end 0.1524 -0.127)
						)
					)
					(width 0)
					(fill yes)
				)
			)
		)
	)
	(footprint ""
		(layer "B.Cu")
		(at 174.59325 -46.102016 180)
		(property "Reference" "C408"
			(at 0 0 0)
			(layer "B.SilkS")
			(hide yes)
			(effects
				(font
					(size 1.27 1.27)
				)
				(justify mirror)
			)
		)
		(property "Value" "SC10U6D3V5KX-4GP"
			(at 0.0762 -6.1214 180)
			(unlocked yes)
			(layer "B.Fab")
			(hide yes)
			(effects
				(font
					(size 1.016 1.016)
					(thickness 0.1524)
				)
				(justify mirror)
			)
		)
		(property "Device Type" "C805H58"
			(at 0.0762 -8.1534 180)
			(unlocked yes)
			(layer "B.Fab")
			(hide yes)
			(effects
				(font
					(size 1.016 1.016)
					(thickness 0.1524)
				)
				(justify mirror)
			)
		)
		(duplicate_pad_numbers_are_jumpers no)
		(fp_line
			(start -0.635 0)
			(end 0.635 0)
			(stroke
				(width 0.508)
				(type default)
			)
			(layer "B.SilkS")
		)
		(fp_rect
			(start 0.9652 1.778)
			(end -0.9652 -1.778)
			(stroke
				(width 0)
				(type default)
			)
			(fill no)
			(layer "B.CrtYd")
		)
		(fp_poly
			(pts
				(xy 0.9652 -1.778) (xy -0.9652 -1.778) (xy -0.9652 1.778) (xy 0.9652 1.778)
			)
			(stroke
				(width 0)
				(type default)
			)
			(fill no)
			(layer "B.Fab")
		)
		(pad "1" smd rect
			(at 0 -0.9652)
			(size 1.397 1.143)
			(layers "B.Cu" "B.Mask" "B.Paste")
			(net "P0V975")
		)
		(pad "2" smd rect
			(at 0 0.9652)
			(size 1.397 1.143)
			(layers "B.Cu" "B.Mask" "B.Paste")
			(net "GND")
		)
	)
	(footprint ""
		(layer "B.Cu")
		(at 183.261 -51.4604 -90)
		(property "Reference" "TP113"
			(at 0 0 90)
			(layer "B.SilkS")
			(hide yes)
			(effects
				(font
					(size 1.27 1.27)
				)
				(justify mirror)
			)
		)
		(property "Value" "TPAD28-2-GP"
			(at 0.0127 -1.6637 270)
			(unlocked yes)
			(layer "B.Fab")
			(hide yes)
			(effects
				(font
					(size 1.016 1.016)
					(thickness 0.1524)
				)
				(justify mirror)
			)
		)
		(property "Device Type" "TPAD28"
			(at 0.0127 -3.1877 270)
			(unlocked yes)
			(layer "B.Fab")
			(hide yes)
			(effects
				(font
					(size 1.016 1.016)
					(thickness 0.1524)
				)
				(justify mirror)
			)
		)
		(duplicate_pad_numbers_are_jumpers no)
		(fp_poly
			(pts
				(arc
					(start 0 -0.3556)
					(mid 0 0.3556)
					(end 0 -0.3556)
				)
			)
			(stroke
				(width 0)
				(type default)
			)
			(fill no)
			(layer "B.CrtYd")
		)
		(fp_poly
			(pts
				(arc
					(start 0 -0.6096)
					(mid 0 0.6096)
					(end 0 -0.6096)
				)
			)
			(stroke
				(width 0)
				(type default)
			)
			(fill no)
			(layer "B.Fab")
		)
		(pad "1" smd circle
			(at 0 0 90)
			(size 0.7112 0.7112)
			(layers "B.Cu" "B.Mask" "B.Paste")
			(net "XM_WP")
		)
	)
	(footprint ""
		(layer "B.Cu")
		(at 189.032388 -30.613858 90)
		(property "Reference" "TP69"
			(at 0 0 90)
			(layer "B.SilkS")
			(hide yes)
			(effects
				(font
					(size 1.27 1.27)
				)
				(justify mirror)
			)
		)
		(property "Value" "TPAD28-2-GP"
			(at 0.0127 -1.6637 90)
			(unlocked yes)
			(layer "B.Fab")
			(hide yes)
			(effects
				(font
					(size 1.016 1.016)
					(thickness 0.1524)
				)
				(justify mirror)
			)
		)
		(property "Device Type" "TPAD28"
			(at 0.0127 -3.1877 90)
			(unlocked yes)
			(layer "B.Fab")
			(hide yes)
			(effects
				(font
					(size 1.016 1.016)
					(thickness 0.1524)
				)
				(justify mirror)
			)
		)
		(duplicate_pad_numbers_are_jumpers no)
		(fp_poly
			(pts
				(arc
					(start 0 0.3556)
					(mid 0 -0.3556)
					(end 0 0.3556)
				)
			)
			(stroke
				(width 0)
				(type default)
			)
			(fill no)
			(layer "B.CrtYd")
		)
		(fp_poly
			(pts
				(arc
					(start 0 0.6096)
					(mid 0 -0.6096)
					(end 0 0.6096)
				)
			)
			(stroke
				(width 0)
				(type default)
			)
			(fill no)
			(layer "B.Fab")
		)
		(pad "1" smd circle
			(at 0 0 270)
			(size 0.7112 0.7112)
			(layers "B.Cu" "B.Mask" "B.Paste")
			(net "IOC_GPIO_16")
		)
	)
)
